(kicad_pcb
	(version 20241229)
	(generator "pcbnew")
	(generator_version "9.0")
	(general
		(thickness 1.61)
		(legacy_teardrops no)
	)
	(paper "A3")
	(title_block
		(title "SO-DIMM DDR5 Tester")
		(date "2025-11-26")
		(rev "1.3.0")
		(comment 9 "footprint 59 of 627 (U4), pads 73-143 of 676")
	)
	(layers
		(0 "F.Cu" signal)
		(4 "In1.Cu" power)
		(6 "In2.Cu" mixed)
		(8 "In3.Cu" power)
		(10 "In4.Cu" mixed)
		(12 "In5.Cu" power)
		(14 "In6.Cu" mixed)
		(16 "In7.Cu" power)
		(18 "In8.Cu" power)
		(20 "In9.Cu" mixed)
		(22 "In10.Cu" power)
		(2 "B.Cu" signal)
		(9 "F.Adhes" user "F.Adhesive")
		(11 "B.Adhes" user "B.Adhesive")
		(13 "F.Paste" user)
		(15 "B.Paste" user)
		(5 "F.SilkS" user "F.Silkscreen")
		(7 "B.SilkS" user "B.Silkscreen")
		(1 "F.Mask" user)
		(3 "B.Mask" user)
		(17 "Dwgs.User" user "User.Drawings")
		(19 "Cmts.User" user "User.Comments")
		(21 "Eco1.User" user "User.Eco1")
		(23 "Eco2.User" user "User.Eco2")
		(25 "Edge.Cuts" user)
		(27 "Margin" user)
		(31 "F.CrtYd" user "F.Courtyard")
		(29 "B.CrtYd" user "B.Courtyard")
		(35 "F.Fab" user)
		(33 "B.Fab" user)
	)
	(footprint "antmicro-footprints:BGA-676_27x27mm_Layout26x26_P1x1mm_FFG676"
		(layer "F.Cu")
		(at 138.875501 174.801 180)
		(descr "FPGA XC7K160TFBG676")
		(tags "FPGA XC7K160TFBG676")
		(property "Reference" "U4"
			(at -12.224499 14.051 180)
			(layer "F.SilkS")
			(effects
				(font
					(size 0.7 0.7)
					(thickness 0.15)
				)
				(justify left bottom)
			)
		)
		(property "Value" "XC7K160T-FFG676"
			(at 0 15.5 180)
			(layer "F.Fab")
			(effects
				(font
					(size 0.7 0.7)
					(thickness 0.15)
				)
				(justify left bottom)
			)
		)
		(property "Datasheet" "https://docs.xilinx.com/v/u/en-US/ds180_7Series_Overview"
			(at 0 0 180)
			(layer "F.Fab")
			(hide yes)
			(effects
				(font
					(size 1.27 1.27)
					(thickness 0.15)
				)
			)
		)
		(property "Author" "Antmicro"
			(at 277.751002 349.602 0)
			(layer "F.Fab")
			(hide yes)
			(effects
				(font
					(size 1 1)
					(thickness 0.15)
				)
			)
		)
		(property "License" "Apache-2.0"
			(at 277.751002 349.602 0)
			(layer "F.Fab")
			(hide yes)
			(effects
				(font
					(size 1 1)
					(thickness 0.15)
				)
			)
		)
		(property "MPN" "XC7K160T-FFG676"
			(at 277.751002 349.602 0)
			(layer "F.Fab")
			(hide yes)
			(effects
				(font
					(size 1 1)
					(thickness 0.15)
				)
			)
		)
		(property "Manufacturer" "AMD-Xilinx"
			(at 277.751002 349.602 0)
			(layer "F.Fab")
			(hide yes)
			(effects
				(font
					(size 1 1)
					(thickness 0.15)
				)
			)
		)
		(sheetname "/FPGA Config/")
		(sheetfile "fpga-config.kicad_sch")
		(attr smd)
		(pad "AB21" smd circle
			(at 7.499 8.499 180)
			(size 0.5 0.5)
			(layers "F.Cu" "F.Mask" "F.Paste")
			(net 273 "RFU_1")
			(pinfunction "IO_L18P_T2_12")
			(pintype "bidirectional")
			(die_length 11.49)
		)
		(pad "AB22" smd circle
			(at 8.499 8.499 180)
			(size 0.5 0.5)
			(layers "F.Cu" "F.Mask" "F.Paste")
			(net 274 "RFU_3")
			(pinfunction "IO_L17P_T2_12")
			(pintype "bidirectional")
			(die_length 12.162)
		)
		(pad "AB23" smd circle
			(at 9.499 8.499 180)
			(size 0.5 0.5)
			(layers "F.Cu" "F.Mask" "F.Paste")
			(net 1 "GND")
			(pinfunction "GND")
			(pintype "passive")
		)
		(pad "AB24" smd circle
			(at 10.499 8.499 180)
			(size 0.5 0.5)
			(layers "F.Cu" "F.Mask" "F.Paste")
			(net 398 "unconnected-(U4A-IO_L11N_T1_SRCC_12-PadAB24)")
			(pinfunction "IO_L11N_T1_SRCC_12")
			(pintype "bidirectional+no_connect")
			(die_length 14.571)
		)
		(pad "AB25" smd circle
			(at 11.499 8.499 180)
			(size 0.5 0.5)
			(layers "F.Cu" "F.Mask" "F.Paste")
			(net 399 "unconnected-(U4A-IO_L7N_T1_12-PadAB25)")
			(pinfunction "IO_L7N_T1_12")
			(pintype "bidirectional+no_connect")
			(die_length 16.017)
		)
		(pad "AB26" smd circle
			(at 12.499 8.499 180)
			(size 0.5 0.5)
			(layers "F.Cu" "F.Mask" "F.Paste")
			(net 680 "/Ethernet/ETH.MDIO")
			(pinfunction "IO_L9P_T1_DQS_12")
			(pintype "bidirectional")
			(die_length 16.487)
		)
		(pad "AC1" smd circle
			(at -12.5 9.499 180)
			(size 0.5 0.5)
			(layers "F.Cu" "F.Mask" "F.Paste")
			(net 265 "/DDR5 SODIMM/B.DQS2_N")
			(pinfunction "IO_L9N_T1_DQS_34")
			(pintype "bidirectional")
			(die_length 21.84)
		)
		(pad "AC2" smd circle
			(at -11.5 9.499 180)
			(size 0.5 0.5)
			(layers "F.Cu" "F.Mask" "F.Paste")
			(net 262 "/DDR5 SODIMM/B.DQ19")
			(pinfunction "IO_L11N_T1_SRCC_34")
			(pintype "bidirectional")
			(die_length 21.727)
		)
		(pad "AC3" smd circle
			(at -10.5 9.499 180)
			(size 0.5 0.5)
			(layers "F.Cu" "F.Mask" "F.Paste")
			(net 255 "/DDR5 SODIMM/B.DQ12")
			(pinfunction "IO_L14N_T2_SRCC_34")
			(pintype "bidirectional")
			(die_length 20.603)
		)
		(pad "AC4" smd circle
			(at -9.5 9.499 180)
			(size 0.5 0.5)
			(layers "F.Cu" "F.Mask" "F.Paste")
			(net 256 "/DDR5 SODIMM/B.DQ13")
			(pinfunction "IO_L14P_T2_SRCC_34")
			(pintype "bidirectional")
			(die_length 20.232)
		)
		(pad "AC5" smd circle
			(at -8.5 9.499 180)
			(size 0.5 0.5)
			(layers "F.Cu" "F.Mask" "F.Paste")
			(net 206 "+1V1")
			(pinfunction "VCCO_34")
			(pintype "passive")
		)
		(pad "AC6" smd circle
			(at -7.5 9.499 180)
			(size 0.5 0.5)
			(layers "F.Cu" "F.Mask" "F.Paste")
			(net 247 "/DDR5 SODIMM/B.DQ11")
			(pinfunction "IO_L16N_T2_34")
			(pintype "bidirectional")
			(die_length 19.298)
		)
		(pad "AC7" smd circle
			(at -6.5 9.499 180)
			(size 0.5 0.5)
			(layers "F.Cu" "F.Mask" "F.Paste")
			(net 154 "/DDR5 SODIMM/A.CA10")
			(pinfunction "IO_L10N_T1_33")
			(pintype "bidirectional")
			(die_length 16.292)
		)
		(pad "AC8" smd circle
			(at -5.5 9.499 180)
			(size 0.5 0.5)
			(layers "F.Cu" "F.Mask" "F.Paste")
			(net 152 "/DDR5 SODIMM/A.CA8")
			(pinfunction "IO_L9P_T1_DQS_33")
			(pintype "bidirectional")
			(die_length 16.788)
		)
		(pad "AC9" smd circle
			(at -4.5 9.499 180)
			(size 0.5 0.5)
			(layers "F.Cu" "F.Mask" "F.Paste")
			(net 148 "/DDR5 SODIMM/A.CA4")
			(pinfunction "IO_L12P_T1_MRCC_33")
			(pintype "bidirectional")
			(die_length 16.857)
		)
		(pad "AC10" smd circle
			(at -3.5 9.499 180)
			(size 0.5 0.5)
			(layers "F.Cu" "F.Mask" "F.Paste")
			(net 1 "GND")
			(pinfunction "GND")
			(pintype "passive")
		)
		(pad "AC11" smd circle
			(at -2.5 9.499 180)
			(size 0.5 0.5)
			(layers "F.Cu" "F.Mask" "F.Paste")
			(net 159 "/DDR5 SODIMM/A.CK0_N")
			(pinfunction "IO_L13N_T2_MRCC_33")
			(pintype "bidirectional")
			(die_length 17.813)
		)
		(pad "AC12" smd circle
			(at -1.5 9.499 180)
			(size 0.5 0.5)
			(layers "F.Cu" "F.Mask" "F.Paste")
			(net 136 "/DDR5 SODIMM/A.CA1")
			(pinfunction "IO_L15N_T2_DQS_33")
			(pintype "bidirectional")
			(die_length 18.956)
		)
		(pad "AC13" smd circle
			(at -0.5 9.499 180)
			(size 0.5 0.5)
			(layers "F.Cu" "F.Mask" "F.Paste")
			(net 147 "/DDR5 SODIMM/A.CA3")
			(pinfunction "IO_L17P_T2_33")
			(pintype "bidirectional")
			(die_length 21.425)
		)
		(pad "AC14" smd circle
			(at 0.499 9.499 180)
			(size 0.5 0.5)
			(layers "F.Cu" "F.Mask" "F.Paste")
			(net 98 "/DDR5 SODIMM/A.DQ21")
			(pinfunction "IO_L8P_T1_32")
			(pintype "bidirectional")
			(die_length 15.875)
		)
		(pad "AC15" smd circle
			(at 1.499 9.499 180)
			(size 0.5 0.5)
			(layers "F.Cu" "F.Mask" "F.Paste")
			(net 206 "+1V1")
			(pinfunction "VCCO_32")
			(pintype "passive")
		)
		(pad "AC16" smd circle
			(at 2.499 9.499 180)
			(size 0.5 0.5)
			(layers "F.Cu" "F.Mask" "F.Paste")
			(net 93 "/DDR5 SODIMM/A.DQ19")
			(pinfunction "IO_L12N_T1_MRCC_32")
			(pintype "bidirectional")
			(die_length 17.396)
		)
		(pad "AC17" smd circle
			(at 3.499 9.499 180)
			(size 0.5 0.5)
			(layers "F.Cu" "F.Mask" "F.Paste")
			(net 87 "/DDR5 SODIMM/A.DQ14")
			(pinfunction "IO_L14N_T2_SRCC_32")
			(pintype "bidirectional")
			(die_length 17.38)
		)
		(pad "AC18" smd circle
			(at 4.499 9.499 180)
			(size 0.5 0.5)
			(layers "F.Cu" "F.Mask" "F.Paste")
			(net 84 "/DDR5 SODIMM/A.DQ12")
			(pinfunction "IO_L13P_T2_MRCC_32")
			(pintype "bidirectional")
			(die_length 20.008)
		)
		(pad "AC19" smd circle
			(at 5.499 9.499 180)
			(size 0.5 0.5)
			(layers "F.Cu" "F.Mask" "F.Paste")
			(net 83 "/DDR5 SODIMM/A.~{DM1}")
			(pinfunction "IO_L17P_T2_32")
			(pintype "bidirectional")
			(die_length 22.343)
		)
		(pad "AC20" smd circle
			(at 6.499 9.499 180)
			(size 0.5 0.5)
			(layers "F.Cu" "F.Mask" "F.Paste")
			(net 1 "GND")
			(pinfunction "GND")
			(pintype "passive")
		)
		(pad "AC21" smd circle
			(at 7.499 9.499 180)
			(size 0.5 0.5)
			(layers "F.Cu" "F.Mask" "F.Paste")
			(net 637 "/DDR5 SODIMM/Control.PWR_EN")
			(pinfunction "IO_L18N_T2_12")
			(pintype "bidirectional")
			(die_length 11.327)
		)
		(pad "AC22" smd circle
			(at 8.499 9.499 180)
			(size 0.5 0.5)
			(layers "F.Cu" "F.Mask" "F.Paste")
			(net 101 "RFU_2")
			(pinfunction "IO_L17N_T2_12")
			(pintype "bidirectional")
			(die_length 12.08)
		)
		(pad "AC23" smd circle
			(at 9.499 9.499 180)
			(size 0.5 0.5)
			(layers "F.Cu" "F.Mask" "F.Paste")
			(net 400 "unconnected-(U4A-IO_L14P_T2_SRCC_12-PadAC23)")
			(pinfunction "IO_L14P_T2_SRCC_12")
			(pintype "bidirectional+no_connect")
			(die_length 13.919)
		)
		(pad "AC24" smd circle
			(at 10.499 9.499 180)
			(size 0.5 0.5)
			(layers "F.Cu" "F.Mask" "F.Paste")
			(net 623 "/FPGA bank 12/HyperRAM.~{RESET}")
			(pinfunction "IO_L14N_T2_SRCC_12")
			(pintype "bidirectional")
			(die_length 13.859)
		)
		(pad "AC25" smd circle
			(at 11.499 9.499 180)
			(size 0.5 0.5)
			(layers "F.Cu" "F.Mask" "F.Paste")
			(net 200 "+3V3")
			(pinfunction "VCCO_12")
			(pintype "passive")
		)
		(pad "AC26" smd circle
			(at 12.499 9.499 180)
			(size 0.5 0.5)
			(layers "F.Cu" "F.Mask" "F.Paste")
			(net 624 "/FPGA bank 12/HyperRAM.~{CS}")
			(pinfunction "IO_L9N_T1_DQS_12")
			(pintype "bidirectional")
			(die_length 17.028)
		)
		(pad "AD1" smd circle
			(at -12.5 10.499 180)
			(size 0.5 0.5)
			(layers "F.Cu" "F.Mask" "F.Paste")
			(net 219 "/DDR5 SODIMM/B.DQ7")
			(pinfunction "IO_L20P_T3_34")
			(pintype "bidirectional")
			(die_length 23.961)
		)
		(pad "AD2" smd circle
			(at -11.5 10.499 180)
			(size 0.5 0.5)
			(layers "F.Cu" "F.Mask" "F.Paste")
			(net 206 "+1V1")
			(pinfunction "VCCO_34")
			(pintype "passive")
		)
		(pad "AD3" smd circle
			(at -10.5 10.499 180)
			(size 0.5 0.5)
			(layers "F.Cu" "F.Mask" "F.Paste")
			(net 10 "/FPGA banks HP/VREF")
			(pinfunction "IO_L19N_T3_VREF_34")
			(pintype "bidirectional")
			(die_length 21.156)
		)
		(pad "AD4" smd circle
			(at -9.5 10.499 180)
			(size 0.5 0.5)
			(layers "F.Cu" "F.Mask" "F.Paste")
			(net 196 "/DDR5 SODIMM/B.DQ1")
			(pinfunction "IO_L19P_T3_34")
			(pintype "bidirectional")
			(die_length 21.197)
		)
		(pad "AD5" smd circle
			(at -8.5 10.499 180)
			(size 0.5 0.5)
			(layers "F.Cu" "F.Mask" "F.Paste")
			(net 254 "/DDR5 SODIMM/B.~{DM1}")
			(pinfunction "IO_L18N_T2_34")
			(pintype "bidirectional")
			(die_length 19.989)
		)
		(pad "AD6" smd circle
			(at -7.5 10.499 180)
			(size 0.5 0.5)
			(layers "F.Cu" "F.Mask" "F.Paste")
			(net 189 "/DDR5 SODIMM/B.CB0")
			(pinfunction "IO_L18P_T2_34")
			(pintype "bidirectional")
			(die_length 20.498)
		)
		(pad "AD7" smd circle
			(at -6.5 10.499 180)
			(size 0.5 0.5)
			(layers "F.Cu" "F.Mask" "F.Paste")
			(net 1 "GND")
			(pinfunction "GND")
			(pintype "passive")
		)
		(pad "AD8" smd circle
			(at -5.5 10.499 180)
			(size 0.5 0.5)
			(layers "F.Cu" "F.Mask" "F.Paste")
			(net 750 "unconnected-(U4G-IO_L9N_T1_DQS_33-PadAD8)")
			(pinfunction "IO_L9N_T1_DQS_33")
			(pintype "bidirectional+no_connect")
			(die_length 16.577)
		)
		(pad "AD9" smd circle
			(at -4.5 10.499 180)
			(size 0.5 0.5)
			(layers "F.Cu" "F.Mask" "F.Paste")
			(net 151 "/DDR5 SODIMM/A.CA7")
			(pinfunction "IO_L12N_T1_MRCC_33")
			(pintype "bidirectional")
			(die_length 17.579)
		)
		(pad "AD10" smd circle
			(at -3.5 10.499 180)
			(size 0.5 0.5)
			(layers "F.Cu" "F.Mask" "F.Paste")
			(net 139 "/DDR5 SODIMM/A.CA2")
			(pinfunction "IO_L20P_T3_33")
			(pintype "bidirectional")
			(die_length 16.019)
		)
		(pad "AD11" smd circle
			(at -2.5 10.499 180)
			(size 0.5 0.5)
			(layers "F.Cu" "F.Mask" "F.Paste")
			(net 121 "/DDR5 SODIMM/A.CA0")
			(pinfunction "IO_L19P_T3_33")
			(pintype "bidirectional")
			(die_length 18.739)
		)
		(pad "AD12" smd circle
			(at -1.5 10.499 180)
			(size 0.5 0.5)
			(layers "F.Cu" "F.Mask" "F.Paste")
			(net 206 "+1V1")
			(pinfunction "VCCO_33")
			(pintype "passive")
		)
		(pad "AD13" smd circle
			(at -0.5 10.499 180)
			(size 0.5 0.5)
			(layers "F.Cu" "F.Mask" "F.Paste")
			(net 122 "/DDR5 SODIMM/Control.~{ALERT}")
			(pinfunction "IO_L17N_T2_33")
			(pintype "bidirectional")
			(die_length 19.307)
		)
		(pad "AD14" smd circle
			(at 0.499 10.499 180)
			(size 0.5 0.5)
			(layers "F.Cu" "F.Mask" "F.Paste")
			(net 97 "/DDR5 SODIMM/A.DQ20")
			(pinfunction "IO_L8N_T1_32")
			(pintype "bidirectional")
			(die_length 17.8)
		)
		(pad "AD15" smd circle
			(at 1.499 10.499 180)
			(size 0.5 0.5)
			(layers "F.Cu" "F.Mask" "F.Paste")
			(net 110 "/DDR5 SODIMM/A.DQ28")
			(pinfunction "IO_L4P_T0_32")
			(pintype "bidirectional")
			(die_length 19.249)
		)
		(pad "AD16" smd circle
			(at 2.499 10.499 180)
			(size 0.5 0.5)
			(layers "F.Cu" "F.Mask" "F.Paste")
			(net 103 "/DDR5 SODIMM/A.DQ25")
			(pinfunction "IO_L6P_T0_32")
			(pintype "bidirectional")
			(die_length 19.246)
		)
		(pad "AD17" smd circle
			(at 3.499 10.499 180)
			(size 0.5 0.5)
			(layers "F.Cu" "F.Mask" "F.Paste")
			(net 1 "GND")
			(pinfunction "GND")
			(pintype "passive")
		)
		(pad "AD18" smd circle
			(at 4.499 10.499 180)
			(size 0.5 0.5)
			(layers "F.Cu" "F.Mask" "F.Paste")
			(net 88 "/DDR5 SODIMM/A.DQ15")
			(pinfunction "IO_L13N_T2_MRCC_32")
			(pintype "bidirectional")
			(die_length 20.423)
		)
		(pad "AD19" smd circle
			(at 5.499 10.499 180)
			(size 0.5 0.5)
			(layers "F.Cu" "F.Mask" "F.Paste")
			(net 85 "/DDR5 SODIMM/A.DQ13")
			(pinfunction "IO_L17N_T2_32")
			(pintype "bidirectional")
			(die_length 20.752)
		)
		(pad "AD20" smd circle
			(at 6.499 10.499 180)
			(size 0.5 0.5)
			(layers "F.Cu" "F.Mask" "F.Paste")
			(net 82 "/DDR5 SODIMM/A.DQS1_P")
			(pinfunction "IO_L15P_T2_DQS_32")
			(pintype "bidirectional")
			(die_length 22.214)
		)
		(pad "AD21" smd circle
			(at 7.499 10.499 180)
			(size 0.5 0.5)
			(layers "F.Cu" "F.Mask" "F.Paste")
			(net 636 "/DDR5 SODIMM/Control.PWR_GOOD")
			(pinfunction "IO_L19P_T3_12")
			(pintype "bidirectional")
			(die_length 13.92)
		)
		(pad "AD22" smd circle
			(at 8.499 10.499 180)
			(size 0.5 0.5)
			(layers "F.Cu" "F.Mask" "F.Paste")
			(net 200 "+3V3")
			(pinfunction "VCCO_12")
			(pintype "passive")
		)
		(pad "AD23" smd circle
			(at 9.499 10.499 180)
			(size 0.5 0.5)
			(layers "F.Cu" "F.Mask" "F.Paste")
			(net 695 "/FPGA bank 12/HyperRAM.RWDS")
			(pinfunction "IO_L16P_T2_12")
			(pintype "bidirectional")
			(die_length 14.54)
		)
		(pad "AD24" smd circle
			(at 10.499 10.499 180)
			(size 0.5 0.5)
			(layers "F.Cu" "F.Mask" "F.Paste")
			(net 701 "/FPGA bank 12/HyperRAM.DQ7")
			(pinfunction "IO_L16N_T2_12")
			(pintype "bidirectional")
			(die_length 14.673)
		)
		(pad "AD25" smd circle
			(at 11.499 10.499 180)
			(size 0.5 0.5)
			(layers "F.Cu" "F.Mask" "F.Paste")
			(net 697 "/FPGA bank 12/HyperRAM.DQ1")
			(pinfunction "IO_L23P_T3_12")
			(pintype "bidirectional")
			(die_length 16.272)
		)
		(pad "AD26" smd circle
			(at 12.499 10.499 180)
			(size 0.5 0.5)
			(layers "F.Cu" "F.Mask" "F.Paste")
			(net 694 "/FPGA bank 12/HyperRAM.CK_P")
			(pinfunction "IO_L21P_T3_DQS_12")
			(pintype "bidirectional")
			(die_length 17.707)
		)
		(pad "AE1" smd circle
			(at -12.5 11.499 180)
			(size 0.5 0.5)
			(layers "F.Cu" "F.Mask" "F.Paste")
			(net 213 "/DDR5 SODIMM/B.DQ6")
			(pinfunction "IO_L20N_T3_34")
			(pintype "bidirectional")
			(die_length 23.86)
		)
		(pad "AE2" smd circle
			(at -11.5 11.499 180)
			(size 0.5 0.5)
			(layers "F.Cu" "F.Mask" "F.Paste")
			(net 212 "/DDR5 SODIMM/B.DQ5")
			(pinfunction "IO_L22N_T3_34")
			(pintype "bidirectional")
			(die_length 25.162)
		)
		(pad "AE3" smd circle
			(at -10.5 11.499 180)
			(size 0.5 0.5)
			(layers "F.Cu" "F.Mask" "F.Paste")
			(net 202 "/DDR5 SODIMM/B.~{DM0}")
			(pinfunction "IO_L22P_T3_34")
			(pintype "bidirectional")
			(die_length 24.57)
		)
		(pad "AE4" smd circle
			(at -9.5 11.499 180)
			(size 0.5 0.5)
			(layers "F.Cu" "F.Mask" "F.Paste")
			(net 1 "GND")
			(pinfunction "GND")
			(pintype "passive")
		)
		(pad "AE5" smd circle
			(at -8.5 11.499 180)
			(size 0.5 0.5)
			(layers "F.Cu" "F.Mask" "F.Paste")
			(net 195 "/DDR5 SODIMM/B.DQ0")
			(pinfunction "IO_L23N_T3_34")
			(pintype "bidirectional")
			(die_length 20.276)
		)
		(pad "AE6" smd circle
			(at -7.5 11.499 180)
			(size 0.5 0.5)
			(layers "F.Cu" "F.Mask" "F.Paste")
			(net 198 "/DDR5 SODIMM/B.DQ3")
			(pinfunction "IO_L23P_T3_34")
			(pintype "bidirectional")
			(die_length 20.819)
		)
		(pad "AE7" smd circle
			(at -6.5 11.499 180)
			(size 0.5 0.5)
			(layers "F.Cu" "F.Mask" "F.Paste")
			(net 191 "/DDR5 SODIMM/B.DQS4_P")
			(pinfunction "IO_L7P_T1_33")
			(pintype "bidirectional")
			(die_length 17.815)
		)
		(pad "AE8" smd circle
			(at -5.5 11.499 180)
			(size 0.5 0.5)
			(layers "F.Cu" "F.Mask" "F.Paste")
			(net 118 "/DDR5 SODIMM/A.DQS4_P")
			(pinfunction "IO_L22P_T3_33")
			(pintype "bidirectional")
			(die_length 19.534)
		)
		(pad "AE9" smd circle
			(at -4.5 11.499 180)
			(size 0.5 0.5)
			(layers "F.Cu" "F.Mask" "F.Paste")
			(net 206 "+1V1")
			(pinfunction "VCCO_33")
			(pintype "passive")
		)
		(pad "AE10" smd circle
			(at -3.5 11.499 180)
			(size 0.5 0.5)
			(layers "F.Cu" "F.Mask" "F.Paste")
			(net 751 "unconnected-(U4G-IO_L20N_T3_33-PadAE10)")
			(pinfunction "IO_L20N_T3_33")
			(pintype "bidirectional+no_connect")
			(die_length 16.714)
		)
		(pad "AE11" smd circle
			(at -2.5 11.499 180)
			(size 0.5 0.5)
			(layers "F.Cu" "F.Mask" "F.Paste")
			(net 10 "/FPGA banks HP/VREF")
			(pinfunction "IO_L19N_T3_VREF_33")
			(pintype "bidirectional")
			(die_length 17.525)
		)
		(pad "AE12" smd circle
			(at -1.5 11.499 180)
			(size 0.5 0.5)
			(layers "F.Cu" "F.Mask" "F.Paste")
			(net 158 "/DDR5 SODIMM/A.CK1_P")
			(pinfunction "IO_L21P_T3_DQS_33")
			(pintype "bidirectional")
			(die_length 19.187)
		)
		(pad "AE13" smd circle
			(at -0.5 11.499 180)
			(size 0.5 0.5)
			(layers "F.Cu" "F.Mask" "F.Paste")
			(net 162 "/DDR5 SODIMM/B.CK1_P")
			(pinfunction "IO_L23P_T3_33")
			(pintype "bidirectional")
			(die_length 20.167)
		)
	)
)
